(kicad_pcb
	(version 20260206)
	(generator "pcbnew")
	(generator_version "10.0")
	(general
		(thickness 1.6)
		(legacy_teardrops no)
	)
	(paper "A4")
	(title_block
		(title "03242023_DA0F0TMBIJ0_F0T_Motherboard_J_brd_V01_OCP.brd")
		(comment 1 "Grand Teton / footprints 3177-3182 of 6105")
	)
	(layers
		(0 "F.Cu" signal "TOP")
		(4 "In1.Cu" signal "GND")
		(6 "In2.Cu" signal "IN1")
		(8 "In3.Cu" signal "GND1")
		(10 "In4.Cu" signal "IN2")
		(12 "In5.Cu" signal "GND2")
		(14 "In6.Cu" signal "IN3")
		(16 "In7.Cu" signal "GND3")
		(18 "In8.Cu" signal "VCC")
		(20 "In9.Cu" signal "VCC1")
		(22 "In10.Cu" signal "GND4")
		(24 "In11.Cu" signal "IN4")
		(26 "In12.Cu" signal "GND5")
		(28 "In13.Cu" signal "IN5")
		(30 "In14.Cu" signal "GND6")
		(32 "In15.Cu" signal "IN6")
		(34 "In16.Cu" signal "GND7")
		(2 "B.Cu" signal "BOTTOM")
		(9 "F.Adhes" user "F.Adhesive")
		(11 "B.Adhes" user "B.Adhesive")
		(13 "F.Paste" user "Package Geometry/Pastemask Top")
		(15 "B.Paste" user "Package Geometry/Pastemask Bottom")
		(5 "F.SilkS" user "Ref Des/Silkscreen Top")
		(7 "B.SilkS" user "Ref Des/Silkscreen Bottom")
		(1 "F.Mask" user "Board Geometry/Soldermask Top")
		(3 "B.Mask" user "Board Geometry/Soldermask Bottom")
		(17 "Dwgs.User" user "User.Drawings")
		(19 "Cmts.User" user "User.Comments")
		(21 "Eco1.User" user "User.Eco1")
		(23 "Eco2.User" user "User.Eco2")
		(25 "Edge.Cuts" user "Board Geometry/Outline")
		(27 "Margin" user)
		(31 "F.CrtYd" user "Package Geometry/Place Bound Top")
		(29 "B.CrtYd" user "Package Geometry/Place Bound Bottom")
		(35 "F.Fab" user "Ref Des/Assembly Top")
		(33 "B.Fab" user "Ref Des/Assembly Bottom")
	)
	(footprint ""
		(layer "F.Cu")
		(at 258.25958 -57.911492 90)
		(property "Reference" "R3975"
			(at 0 0 90)
			(layer "F.SilkS")
			(hide yes)
			(effects
				(font
					(size 1.27 1.27)
				)
			)
		)
		(property "Value" ""
			(at 0 0 90)
			(layer "F.Fab")
			(effects
				(font
					(size 1.27 1.27)
				)
			)
		)
		(duplicate_pad_numbers_are_jumpers no)
		(fp_line
			(start 0.7874 -0.4064)
			(end 0.7874 0.4064)
			(stroke
				(width 0.1524)
				(type default)
			)
			(layer "F.SilkS")
		)
		(fp_line
			(start -0.7874 -0.4064)
			(end 0.7874 -0.4064)
			(stroke
				(width 0.1524)
				(type default)
			)
			(layer "F.SilkS")
		)
		(fp_line
			(start 0.7874 0.4064)
			(end -0.7874 0.4064)
			(stroke
				(width 0.1524)
				(type default)
			)
			(layer "F.SilkS")
		)
		(fp_line
			(start -0.7874 0.4064)
			(end -0.7874 -0.4064)
			(stroke
				(width 0.1524)
				(type default)
			)
			(layer "F.SilkS")
		)
		(fp_line
			(start -0.12065 -0.305054)
			(end -0.12065 -0.2794)
			(stroke
				(width 0.1)
				(type default)
			)
			(layer "F.Fab")
		)
		(fp_line
			(start -0.67945 -0.305054)
			(end -0.12065 -0.305054)
			(stroke
				(width 0.1)
				(type default)
			)
			(layer "F.Fab")
		)
		(fp_line
			(start 0.67945 -0.3048)
			(end 0.67945 0.3048)
			(stroke
				(width 0.1)
				(type default)
			)
			(layer "F.Fab")
		)
		(fp_line
			(start 0.12065 -0.3048)
			(end 0.67945 -0.3048)
			(stroke
				(width 0.1)
				(type default)
			)
			(layer "F.Fab")
		)
		(fp_line
			(start 0.12065 -0.2794)
			(end 0.12065 -0.3048)
			(stroke
				(width 0.1)
				(type default)
			)
			(layer "F.Fab")
		)
		(fp_line
			(start -0.12065 -0.2794)
			(end 0.12065 -0.2794)
			(stroke
				(width 0.1)
				(type default)
			)
			(layer "F.Fab")
		)
		(fp_line
			(start 0.120396 0.2794)
			(end -0.12065 0.2794)
			(stroke
				(width 0.1)
				(type default)
			)
			(layer "F.Fab")
		)
		(fp_line
			(start -0.12065 0.2794)
			(end -0.12065 0.3048)
			(stroke
				(width 0.1)
				(type default)
			)
			(layer "F.Fab")
		)
		(fp_line
			(start 0.67945 0.3048)
			(end 0.120396 0.3048)
			(stroke
				(width 0.1)
				(type default)
			)
			(layer "F.Fab")
		)
		(fp_line
			(start 0.120396 0.3048)
			(end 0.120396 0.2794)
			(stroke
				(width 0.1)
				(type default)
			)
			(layer "F.Fab")
		)
		(fp_line
			(start -0.12065 0.3048)
			(end -0.67945 0.3048)
			(stroke
				(width 0.1)
				(type default)
			)
			(layer "F.Fab")
		)
		(fp_line
			(start -0.67945 0.3048)
			(end -0.67945 -0.305054)
			(stroke
				(width 0.1)
				(type default)
			)
			(layer "F.Fab")
		)
		(pad "1" smd rect
			(at -0.40005 0 270)
			(size 0.4572 0.508)
			(layers "F.Cu" "F.Mask" "F.Paste")
			(net "P12V_E1S_SENSE_0")
		)
		(pad "2" smd rect
			(at 0.40005 0 270)
			(size 0.4572 0.508)
			(layers "F.Cu" "F.Mask" "F.Paste")
			(net "P12V_E1S_0_ISENSE_MAM_TIC")
		)
	)
	(footprint ""
		(layer "F.Cu")
		(at 107.87888 -57.241948)
		(property "Reference" "C1292"
			(at 0 0 0)
			(layer "F.SilkS")
			(hide yes)
			(effects
				(font
					(size 1.27 1.27)
				)
			)
		)
		(property "Value" ""
			(at 0 0 0)
			(layer "F.Fab")
			(effects
				(font
					(size 1.27 1.27)
				)
			)
		)
		(duplicate_pad_numbers_are_jumpers no)
		(fp_line
			(start -0.7874 -0.4064)
			(end 0.7874 -0.4064)
			(stroke
				(width 0.1524)
				(type default)
			)
			(layer "F.SilkS")
		)
		(fp_line
			(start -0.7874 0.4064)
			(end -0.7874 -0.4064)
			(stroke
				(width 0.1524)
				(type default)
			)
			(layer "F.SilkS")
		)
		(fp_line
			(start 0.7874 -0.4064)
			(end 0.7874 0.4064)
			(stroke
				(width 0.1524)
				(type default)
			)
			(layer "F.SilkS")
		)
		(fp_line
			(start 0.7874 0.4064)
			(end -0.7874 0.4064)
			(stroke
				(width 0.1524)
				(type default)
			)
			(layer "F.SilkS")
		)
		(fp_line
			(start -0.67945 -0.305054)
			(end -0.12065 -0.305054)
			(stroke
				(width 0.1)
				(type default)
			)
			(layer "F.Fab")
		)
		(fp_line
			(start -0.67945 0.3048)
			(end -0.67945 -0.305054)
			(stroke
				(width 0.1)
				(type default)
			)
			(layer "F.Fab")
		)
		(fp_line
			(start -0.12065 -0.305054)
			(end -0.12065 -0.2794)
			(stroke
				(width 0.1)
				(type default)
			)
			(layer "F.Fab")
		)
		(fp_line
			(start -0.12065 -0.2794)
			(end 0.12065 -0.2794)
			(stroke
				(width 0.1)
				(type default)
			)
			(layer "F.Fab")
		)
		(fp_line
			(start -0.12065 0.2794)
			(end -0.12065 0.3048)
			(stroke
				(width 0.1)
				(type default)
			)
			(layer "F.Fab")
		)
		(fp_line
			(start -0.12065 0.3048)
			(end -0.67945 0.3048)
			(stroke
				(width 0.1)
				(type default)
			)
			(layer "F.Fab")
		)
		(fp_line
			(start 0.120396 0.2794)
			(end -0.12065 0.2794)
			(stroke
				(width 0.1)
				(type default)
			)
			(layer "F.Fab")
		)
		(fp_line
			(start 0.120396 0.3048)
			(end 0.120396 0.2794)
			(stroke
				(width 0.1)
				(type default)
			)
			(layer "F.Fab")
		)
		(fp_line
			(start 0.12065 -0.3048)
			(end 0.67945 -0.3048)
			(stroke
				(width 0.1)
				(type default)
			)
			(layer "F.Fab")
		)
		(fp_line
			(start 0.12065 -0.2794)
			(end 0.12065 -0.3048)
			(stroke
				(width 0.1)
				(type default)
			)
			(layer "F.Fab")
		)
		(fp_line
			(start 0.67945 -0.3048)
			(end 0.67945 0.3048)
			(stroke
				(width 0.1)
				(type default)
			)
			(layer "F.Fab")
		)
		(fp_line
			(start 0.67945 0.3048)
			(end 0.120396 0.3048)
			(stroke
				(width 0.1)
				(type default)
			)
			(layer "F.Fab")
		)
		(pad "1" smd circle
			(at -0.40005 0)
			(size 0 0)
			(layers "F.Cu" "F.Mask" "F.Paste")
			(net "P3V3_AUX")
		)
		(pad "2" smd circle
			(at 0.40005 0)
			(size 0 0)
			(layers "F.Cu" "F.Mask" "F.Paste")
			(net "GND")
		)
	)
	(footprint ""
		(layer "F.Cu")
		(at 165.15715 -432.865276 90)
		(property "Reference" "R2671"
			(at 0 0 90)
			(layer "F.SilkS")
			(hide yes)
			(effects
				(font
					(size 1.27 1.27)
				)
			)
		)
		(property "Value" ""
			(at 0 0 90)
			(layer "F.Fab")
			(effects
				(font
					(size 1.27 1.27)
				)
			)
		)
		(duplicate_pad_numbers_are_jumpers no)
		(fp_line
			(start 0.7874 -0.4064)
			(end 0.7874 0.4064)
			(stroke
				(width 0.1524)
				(type default)
			)
			(layer "F.SilkS")
		)
		(fp_line
			(start -0.7874 -0.4064)
			(end 0.7874 -0.4064)
			(stroke
				(width 0.1524)
				(type default)
			)
			(layer "F.SilkS")
		)
		(fp_line
			(start 0.7874 0.4064)
			(end -0.7874 0.4064)
			(stroke
				(width 0.1524)
				(type default)
			)
			(layer "F.SilkS")
		)
		(fp_line
			(start -0.7874 0.4064)
			(end -0.7874 -0.4064)
			(stroke
				(width 0.1524)
				(type default)
			)
			(layer "F.SilkS")
		)
		(fp_line
			(start -0.12065 -0.305054)
			(end -0.12065 -0.2794)
			(stroke
				(width 0.1)
				(type default)
			)
			(layer "F.Fab")
		)
		(fp_line
			(start -0.67945 -0.305054)
			(end -0.12065 -0.305054)
			(stroke
				(width 0.1)
				(type default)
			)
			(layer "F.Fab")
		)
		(fp_line
			(start 0.67945 -0.3048)
			(end 0.67945 0.3048)
			(stroke
				(width 0.1)
				(type default)
			)
			(layer "F.Fab")
		)
		(fp_line
			(start 0.12065 -0.3048)
			(end 0.67945 -0.3048)
			(stroke
				(width 0.1)
				(type default)
			)
			(layer "F.Fab")
		)
		(fp_line
			(start 0.12065 -0.2794)
			(end 0.12065 -0.3048)
			(stroke
				(width 0.1)
				(type default)
			)
			(layer "F.Fab")
		)
		(fp_line
			(start -0.12065 -0.2794)
			(end 0.12065 -0.2794)
			(stroke
				(width 0.1)
				(type default)
			)
			(layer "F.Fab")
		)
		(fp_line
			(start 0.120396 0.2794)
			(end -0.12065 0.2794)
			(stroke
				(width 0.1)
				(type default)
			)
			(layer "F.Fab")
		)
		(fp_line
			(start -0.12065 0.2794)
			(end -0.12065 0.3048)
			(stroke
				(width 0.1)
				(type default)
			)
			(layer "F.Fab")
		)
		(fp_line
			(start 0.67945 0.3048)
			(end 0.120396 0.3048)
			(stroke
				(width 0.1)
				(type default)
			)
			(layer "F.Fab")
		)
		(fp_line
			(start 0.120396 0.3048)
			(end 0.120396 0.2794)
			(stroke
				(width 0.1)
				(type default)
			)
			(layer "F.Fab")
		)
		(fp_line
			(start -0.12065 0.3048)
			(end -0.67945 0.3048)
			(stroke
				(width 0.1)
				(type default)
			)
			(layer "F.Fab")
		)
		(fp_line
			(start -0.67945 0.3048)
			(end -0.67945 -0.305054)
			(stroke
				(width 0.1)
				(type default)
			)
			(layer "F.Fab")
		)
		(pad "1" smd circle
			(at -0.40005 0 90)
			(size 0 0)
			(layers "F.Cu" "F.Mask" "F.Paste")
			(net "SMB_BMC_SWB_BUF_R_SCL")
		)
		(pad "2" smd circle
			(at 0.40005 0 90)
			(size 0 0)
			(layers "F.Cu" "F.Mask" "F.Paste")
			(net "SMB_BMC_SWB_BUF_SCL")
		)
	)
	(footprint ""
		(layer "F.Cu")
		(at 367.44783 -249.320304 -90)
		(property "Reference" "C981"
			(at 0 0 270)
			(layer "F.SilkS")
			(hide yes)
			(effects
				(font
					(size 1.27 1.27)
				)
			)
		)
		(property "Value" ""
			(at 0 0 270)
			(layer "F.Fab")
			(effects
				(font
					(size 1.27 1.27)
				)
			)
		)
		(duplicate_pad_numbers_are_jumpers no)
		(fp_line
			(start -0.7874 0.4064)
			(end -0.7874 -0.4064)
			(stroke
				(width 0.1524)
				(type default)
			)
			(layer "F.SilkS")
		)
		(fp_line
			(start 0.7874 0.4064)
			(end -0.7874 0.4064)
			(stroke
				(width 0.1524)
				(type default)
			)
			(layer "F.SilkS")
		)
		(fp_line
			(start -0.7874 -0.4064)
			(end 0.7874 -0.4064)
			(stroke
				(width 0.1524)
				(type default)
			)
			(layer "F.SilkS")
		)
		(fp_line
			(start 0.7874 -0.4064)
			(end 0.7874 0.4064)
			(stroke
				(width 0.1524)
				(type default)
			)
			(layer "F.SilkS")
		)
		(fp_line
			(start -0.67945 0.3048)
			(end -0.67945 -0.305054)
			(stroke
				(width 0.1)
				(type default)
			)
			(layer "F.Fab")
		)
		(fp_line
			(start -0.12065 0.3048)
			(end -0.67945 0.3048)
			(stroke
				(width 0.1)
				(type default)
			)
			(layer "F.Fab")
		)
		(fp_line
			(start 0.120396 0.3048)
			(end 0.120396 0.2794)
			(stroke
				(width 0.1)
				(type default)
			)
			(layer "F.Fab")
		)
		(fp_line
			(start 0.67945 0.3048)
			(end 0.120396 0.3048)
			(stroke
				(width 0.1)
				(type default)
			)
			(layer "F.Fab")
		)
		(fp_line
			(start -0.12065 0.2794)
			(end -0.12065 0.3048)
			(stroke
				(width 0.1)
				(type default)
			)
			(layer "F.Fab")
		)
		(fp_line
			(start 0.120396 0.2794)
			(end -0.12065 0.2794)
			(stroke
				(width 0.1)
				(type default)
			)
			(layer "F.Fab")
		)
		(fp_line
			(start -0.12065 -0.2794)
			(end 0.12065 -0.2794)
			(stroke
				(width 0.1)
				(type default)
			)
			(layer "F.Fab")
		)
		(fp_line
			(start 0.12065 -0.2794)
			(end 0.12065 -0.3048)
			(stroke
				(width 0.1)
				(type default)
			)
			(layer "F.Fab")
		)
		(fp_line
			(start 0.12065 -0.3048)
			(end 0.67945 -0.3048)
			(stroke
				(width 0.1)
				(type default)
			)
			(layer "F.Fab")
		)
		(fp_line
			(start 0.67945 -0.3048)
			(end 0.67945 0.3048)
			(stroke
				(width 0.1)
				(type default)
			)
			(layer "F.Fab")
		)
		(fp_line
			(start -0.67945 -0.305054)
			(end -0.12065 -0.305054)
			(stroke
				(width 0.1)
				(type default)
			)
			(layer "F.Fab")
		)
		(fp_line
			(start -0.12065 -0.305054)
			(end -0.12065 -0.2794)
			(stroke
				(width 0.1)
				(type default)
			)
			(layer "F.Fab")
		)
		(pad "1" smd circle
			(at -0.40005 0 270)
			(size 0 0)
			(layers "F.Cu" "F.Mask" "F.Paste")
			(net "PVCCIN_CPU0")
		)
		(pad "2" smd circle
			(at 0.40005 0 270)
			(size 0 0)
			(layers "F.Cu" "F.Mask" "F.Paste")
			(net "GND")
		)
	)
	(footprint ""
		(layer "F.Cu")
		(at 451.923404 -71.019416 -90)
		(property "Reference" "PC577"
			(at 0 0 270)
			(layer "F.SilkS")
			(hide yes)
			(effects
				(font
					(size 1.27 1.27)
				)
			)
		)
		(property "Value" ""
			(at 0 0 270)
			(layer "F.Fab")
			(effects
				(font
					(size 1.27 1.27)
				)
			)
		)
		(duplicate_pad_numbers_are_jumpers no)
		(fp_line
			(start -0.7874 0.4064)
			(end -0.7874 -0.4064)
			(stroke
				(width 0.1524)
				(type default)
			)
			(layer "F.SilkS")
		)
		(fp_line
			(start 0.7874 0.4064)
			(end -0.7874 0.4064)
			(stroke
				(width 0.1524)
				(type default)
			)
			(layer "F.SilkS")
		)
		(fp_line
			(start -0.7874 -0.4064)
			(end 0.7874 -0.4064)
			(stroke
				(width 0.1524)
				(type default)
			)
			(layer "F.SilkS")
		)
		(fp_line
			(start 0.7874 -0.4064)
			(end 0.7874 0.4064)
			(stroke
				(width 0.1524)
				(type default)
			)
			(layer "F.SilkS")
		)
		(fp_line
			(start -0.67945 0.3048)
			(end -0.67945 -0.305054)
			(stroke
				(width 0.1)
				(type default)
			)
			(layer "F.Fab")
		)
		(fp_line
			(start -0.12065 0.3048)
			(end -0.67945 0.3048)
			(stroke
				(width 0.1)
				(type default)
			)
			(layer "F.Fab")
		)
		(fp_line
			(start 0.120396 0.3048)
			(end 0.120396 0.2794)
			(stroke
				(width 0.1)
				(type default)
			)
			(layer "F.Fab")
		)
		(fp_line
			(start 0.67945 0.3048)
			(end 0.120396 0.3048)
			(stroke
				(width 0.1)
				(type default)
			)
			(layer "F.Fab")
		)
		(fp_line
			(start -0.12065 0.2794)
			(end -0.12065 0.3048)
			(stroke
				(width 0.1)
				(type default)
			)
			(layer "F.Fab")
		)
		(fp_line
			(start 0.120396 0.2794)
			(end -0.12065 0.2794)
			(stroke
				(width 0.1)
				(type default)
			)
			(layer "F.Fab")
		)
		(fp_line
			(start -0.12065 -0.2794)
			(end 0.12065 -0.2794)
			(stroke
				(width 0.1)
				(type default)
			)
			(layer "F.Fab")
		)
		(fp_line
			(start 0.12065 -0.2794)
			(end 0.12065 -0.3048)
			(stroke
				(width 0.1)
				(type default)
			)
			(layer "F.Fab")
		)
		(fp_line
			(start 0.12065 -0.3048)
			(end 0.67945 -0.3048)
			(stroke
				(width 0.1)
				(type default)
			)
			(layer "F.Fab")
		)
		(fp_line
			(start 0.67945 -0.3048)
			(end 0.67945 0.3048)
			(stroke
				(width 0.1)
				(type default)
			)
			(layer "F.Fab")
		)
		(fp_line
			(start -0.67945 -0.305054)
			(end -0.12065 -0.305054)
			(stroke
				(width 0.1)
				(type default)
			)
			(layer "F.Fab")
		)
		(fp_line
			(start -0.12065 -0.305054)
			(end -0.12065 -0.2794)
			(stroke
				(width 0.1)
				(type default)
			)
			(layer "F.Fab")
		)
		(pad "1" smd circle
			(at -0.40005 0 270)
			(size 0 0)
			(layers "F.Cu" "F.Mask" "F.Paste")
			(net "SW_P3V3_AUX_FLT")
		)
		(pad "2" smd circle
			(at 0.40005 0 270)
			(size 0 0)
			(layers "F.Cu" "F.Mask" "F.Paste")
			(net "GND")
		)
	)
	(footprint ""
		(layer "F.Cu")
		(at 86.931246 -57.279286 90)
		(property "Reference" "PR3782"
			(at 0 0 90)
			(layer "F.SilkS")
			(hide yes)
			(effects
				(font
					(size 1.27 1.27)
				)
			)
		)
		(property "Value" ""
			(at 0 0 90)
			(layer "F.Fab")
			(effects
				(font
					(size 1.27 1.27)
				)
			)
		)
		(duplicate_pad_numbers_are_jumpers no)
		(fp_line
			(start 0.7874 -0.4064)
			(end 0.7874 0.4064)
			(stroke
				(width 0.1524)
				(type default)
			)
			(layer "F.SilkS")
		)
		(fp_line
			(start -0.7874 -0.4064)
			(end 0.7874 -0.4064)
			(stroke
				(width 0.1524)
				(type default)
			)
			(layer "F.SilkS")
		)
		(fp_line
			(start 0.7874 0.4064)
			(end -0.7874 0.4064)
			(stroke
				(width 0.1524)
				(type default)
			)
			(layer "F.SilkS")
		)
		(fp_line
			(start -0.7874 0.4064)
			(end -0.7874 -0.4064)
			(stroke
				(width 0.1524)
				(type default)
			)
			(layer "F.SilkS")
		)
		(fp_line
			(start -0.12065 -0.305054)
			(end -0.12065 -0.2794)
			(stroke
				(width 0.1)
				(type default)
			)
			(layer "F.Fab")
		)
		(fp_line
			(start -0.67945 -0.305054)
			(end -0.12065 -0.305054)
			(stroke
				(width 0.1)
				(type default)
			)
			(layer "F.Fab")
		)
		(fp_line
			(start 0.67945 -0.3048)
			(end 0.67945 0.3048)
			(stroke
				(width 0.1)
				(type default)
			)
			(layer "F.Fab")
		)
		(fp_line
			(start 0.12065 -0.3048)
			(end 0.67945 -0.3048)
			(stroke
				(width 0.1)
				(type default)
			)
			(layer "F.Fab")
		)
		(fp_line
			(start 0.12065 -0.2794)
			(end 0.12065 -0.3048)
			(stroke
				(width 0.1)
				(type default)
			)
			(layer "F.Fab")
		)
		(fp_line
			(start -0.12065 -0.2794)
			(end 0.12065 -0.2794)
			(stroke
				(width 0.1)
				(type default)
			)
			(layer "F.Fab")
		)
		(fp_line
			(start 0.120396 0.2794)
			(end -0.12065 0.2794)
			(stroke
				(width 0.1)
				(type default)
			)
			(layer "F.Fab")
		)
		(fp_line
			(start -0.12065 0.2794)
			(end -0.12065 0.3048)
			(stroke
				(width 0.1)
				(type default)
			)
			(layer "F.Fab")
		)
		(fp_line
			(start 0.67945 0.3048)
			(end 0.120396 0.3048)
			(stroke
				(width 0.1)
				(type default)
			)
			(layer "F.Fab")
		)
		(fp_line
			(start 0.120396 0.3048)
			(end 0.120396 0.2794)
			(stroke
				(width 0.1)
				(type default)
			)
			(layer "F.Fab")
		)
		(fp_line
			(start -0.12065 0.3048)
			(end -0.67945 0.3048)
			(stroke
				(width 0.1)
				(type default)
			)
			(layer "F.Fab")
		)
		(fp_line
			(start -0.67945 0.3048)
			(end -0.67945 -0.305054)
			(stroke
				(width 0.1)
				(type default)
			)
			(layer "F.Fab")
		)
		(pad "1" smd circle
			(at -0.40005 0 90)
			(size 0 0)
			(layers "F.Cu" "F.Mask" "F.Paste")
			(net "P3V3_AUX")
		)
		(pad "2" smd circle
			(at 0.40005 0 90)
			(size 0 0)
			(layers "F.Cu" "F.Mask" "F.Paste")
			(net "P3V3_OCP_VCC_2")
		)
	)
)
